# ZAIUS-MB-PVT-X04-BOM_X31_20180131_Final.xls.xlsx — Summary (bom)
| PLATFORM SOURCING AND PSL COMPLIANCE |  |  |  |  |  |  |  |  |  |
| Platform Name: |  |  |  |  |  |  |  |  |  |
| REVISION HISTORY |  |  |  |  |  |  |  |  |  |
| BOM Revision: | ECR # | Revision Description | Originator | Date |  |  |  |  |  |
| X23 |  | DVT |  | 42901 |  |  |  |  |  |
| X31 |  |  |  | 43131 |  |  |  |  |  |
| Commodity Sourcing | # of components (X00 BOM) | % of Total | # of components (X01 BOM) | % of Total | # of components (X02 BOM) | % of Total | # of components (RTS) | % of Total | Risk Mitigation Plans in Place |
| Sole Source |  |  |  |  | 80 | 0.1830663616 |  |  |  |
| Single Source |  |  |  |  | 31 | 0.0709382151 |  |  |  |
| Multiple |  |  |  |  | 326 | 0.7459954233 |  |  | NA |
| Total |  |  |  |  | 437 | 1 |  |  | NA |
|  |  | # of components | # of components aligned with Customer PSL* | % PSL alignment |  |  |  |  |  |
| Class 1 (Customer Managed) |  |  |  |  |  |  |  |  |  |
| Class 2 (ODM Managed to Customer PSL) |  |  |  |  |  |  |  |  |  |
| All other components(ODM Managed to ODM PSL) |  |  |  |  |  |  |  |  |  |
| *RFQ and/or Contract will list requirements for complying with Customer's PSL |  |  |  |  |  |  |  |  |  |
| Reference for quotation |  |  |  |  |  |  |  |  |  |
